# S9S_MB_2U (Grand Teton) — schematic netlist excerpt (pin names and nets, part order shuffled) for the footprints in the layout excerpt that follows; sources: Cadence DE-HDL packaged netlist, KiCad conversion of 03242023_DA0F0TMBIJ0_F0T_Motherboard_J_brd_V01_OCP.brd

J32  SCONN288_ADR50017P087CC  SCONN288_ADR50017-P087CC IO  pkg DDR288S_1-1VXB  page 113
  VIN_BULK0  = P12V_S3_AUX_CPU1_NVDIMM
  RFU0  = TP_CHH_CPU1_DIMM2_FRU_0
  VIN_MGMT  = P3V3_AUX
  HSCL  = I3C_SPD_DDREFGH_CPU1_LVC1_SCL_7
  HSDA  = I3C_SPD_DDREFGH_CPU1_LVC1_SDA
  VSS0  = GND
  DQ0_A  = M_H_CPU1_SA_DQ<0>
  VSS1  = GND
  DQ1_A  = M_H_CPU1_SA_DQ<1>
  VSS2  = GND
  DQS0_A_T  = M_H_CPU1_SA_DQS_DP<0>
  DQS0_A_C  = M_H_CPU1_SA_DQS_DN<0>
  VSS3  = GND
  DQ4_A  = M_H_CPU1_SA_DQ<4>
  VSS4  = GND
  DQ5_A  = M_H_CPU1_SA_DQ<5>
  VSS5  = GND
  DQ8_A  = M_H_CPU1_SA_DQ<8>
  VSS6  = GND
  DQ9_A  = M_H_CPU1_SA_DQ<9>
  VSS7  = GND
  DQS1_A_T  = M_H_CPU1_SA_DQS_DP<1>
  DQS1_A_C  = M_H_CPU1_SA_DQS_DN<1>
  VSS8  = GND
  DQ12_A  = M_H_CPU1_SA_DQ<12>
  VSS9  = GND
  DQ13_A  = M_H_CPU1_SA_DQ<13>
  VSS10  = GND
  DQ16_A  = M_H_CPU1_SA_DQ<16>
  VSS11  = GND
  DQ17_A  = M_H_CPU1_SA_DQ<17>
  VSS12  = GND
  DQS2_A_T  = M_H_CPU1_SA_DQS_DP<2>
  DQS2_A_C  = M_H_CPU1_SA_DQS_DN<2>
  VSS13  = GND
  DQ20_A  = M_H_CPU1_SA_DQ<20>
  VSS14  = GND
  DQ21_A  = M_H_CPU1_SA_DQ<21>
  VSS15  = GND
  DQ24_A  = M_H_CPU1_SA_DQ<24>
  VSS16  = GND
  DQ25_A  = M_H_CPU1_SA_DQ<25>
  VSS17  = GND
  DQS3_A_T  = M_H_CPU1_SA_DQS_DP<3>
  DQS3_A_C  = M_H_CPU1_SA_DQS_DN<3>
  VSS18  = GND
  DQ28_A  = M_H_CPU1_SA_DQ<28>
  VSS19  = GND
  DQ29_A  = M_H_CPU1_SA_DQ<29>
  VSS20  = GND
  CB0_A  = M_H_CPU1_SA_CB<0>
  VSS21  = GND
  CB1_A  = M_H_CPU1_SA_CB<1>
  VSS22  = GND
  DQS4_A_T  = M_H_CPU1_SA_DQS_DP<4>
  DQS4_A_C  = M_H_CPU1_SA_DQS_DN<4>
  VSS23  = GND
  CB4_A  = M_H_CPU1_SA_CB<4>
  VSS24  = GND
  CB5_A  = M_H_CPU1_SA_CB<5>
  VSS25  = GND
  ALERT_N  = M_H_CPU1_ALERT_N
  VSS26  = GND
  CS0_A_N  = M_H_CPU1_SA_CS_N<2>
  VSS27  = GND
  CA0_A  = M_H_CPU1_SA_CA<0>
  VSS28  = GND
  CA2_A  = M_H_CPU1_SA_CA<2>
  VSS29  = GND
  CA4_A  = M_H_CPU1_SA_CA<4>
  VSS30  = GND
  CA6_A  = M_H_CPU1_SA_CA<6>
  VSS31  = GND
  PAR_A  = M_H_CPU1_SA_PAR
  VSS32  = GND
  CA0_B  = M_H_CPU1_SB_CA<0>
  VSS33  = GND
  CA2_B  = M_H_CPU1_SB_CA<2>
  VSS34  = GND
  CA4_B  = M_H_CPU1_SB_CA<4>
  VSS35  = GND
  CA6_B  = M_H_CPU1_SB_CA<6>
  VSS36  = GND
  CS0_B_N  = M_H_CPU1_SB_CS_N<2>
  VSS37  = GND
  \lbd||rsp_a_n\  = M_H_CPU1_SA_RSP<1>
  \lbs||rsp_b_n\  = M_H_CPU1_SB_RSP<1>
  VSS38  = GND
  CB4_B  = M_H_CPU1_SB_CB<4>
  VSS39  = GND
  CB5_B  = M_H_CPU1_SB_CB<5>
  VSS40  = GND
  \dqs9_b_t||tdqs9_b_t||dbi4_b_n\  = M_H_CPU1_SB_DQS_DP<9>
  \dqs9_b_c||tdqs9_b_c\  = M_H_CPU1_SB_DQS_DN<9>
  VSS41  = GND
  CB0_B  = M_H_CPU1_SB_CB<0>
  VSS42  = GND
  CB1_B  = M_H_CPU1_SB_CB<1>
  VSS43  = GND
  DQ0_B  = M_H_CPU1_SB_DQ<0>
  VSS44  = GND
  DQ1_B  = M_H_CPU1_SB_DQ<1>
  VSS45  = GND
  DQS0_B_T  = M_H_CPU1_SB_DQS_DP<0>
  DQS0_B_C  = M_H_CPU1_SB_DQS_DN<0>
  VSS46  = GND
  DQ4_B  = M_H_CPU1_SB_DQ<4>
  VSS47  = GND
  DQ5_B  = M_H_CPU1_SB_DQ<5>
  VSS48  = GND
  DQ8_B  = M_H_CPU1_SB_DQ<8>
  VSS49  = GND
  DQ9_B  = M_H_CPU1_SB_DQ<9>
  VSS50  = GND
  DQS1_B_T  = M_H_CPU1_SB_DQS_DP<1>
  DQS1_B_C  = M_H_CPU1_SB_DQS_DN<1>
  VSS51  = GND
  DQ12_B  = M_H_CPU1_SB_DQ<12>
  VSS52  = GND
  DQ13_B  = M_H_CPU1_SB_DQ<13>
  VSS53  = GND
  DQ16_B  = M_H_CPU1_SB_DQ<16>
  VSS54  = GND
  DQ17_B  = M_H_CPU1_SB_DQ<17>
  VSS55  = GND
  DQS2_B_T  = M_H_CPU1_SB_DQS_DP<2>
  DQS2_B_C  = M_H_CPU1_SB_DQS_DN<2>
  VSS56  = GND
  DQ20_B  = M_H_CPU1_SB_DQ<20>
  VSS57  = GND
  DQ21_B  = M_H_CPU1_SB_DQ<21>
  VSS58  = GND
  DQ24_B  = M_H_CPU1_SB_DQ<24>
  VSS59  = GND
  DQ25_B  = M_H_CPU1_SB_DQ<25>
  VSS60  = GND
  DQS3_B_T  = M_H_CPU1_SB_DQS_DP<3>
  DQS3_B_C  = M_H_CPU1_SB_DQS_DN<3>
  VSS61  = GND
  DQ28_B  = M_H_CPU1_SB_DQ<28>
  VSS62  = GND
  DQ29_B  = M_H_CPU1_SB_DQ<29>
  VSS63  = GND
  RFU1  = TP_CHH_CPU1_DIMM2_FRU_1
  VIN_BULK1  = P12V_S3_AUX_CPU1_NVDIMM
  VIN_BULK2  = P12V_S3_AUX_CPU1_NVDIMM
  \pwr_good||fail_n\  = PWRGD_CHH_CPU1_DIMM2
  HSA  = PD_CHH_CPU1_DIMM2_SAA
  RFU2  = TP_CHH_CPU1_DIMM2_FRU_2
  RFU3  = TP_CHH_CPU1_DIMM2_FRU_3
  VSS64  = GND
  DQ2_A  = M_H_CPU1_SA_DQ<2>
  VSS65  = GND
  DQ3_A  = M_H_CPU1_SA_DQ<3>
  VSS66  = GND
  \dqs5_a_c||tdqs5_a_c||dqs5_a_t||tdqs5_a_t\  = M_H_CPU1_SA_DQS_DN<5>
  \dqs5_a_t||tdqs5_a_t\  = M_H_CPU1_SA_DQS_DP<5>
  VSS67  = GND
  DQ6_A  = M_H_CPU1_SA_DQ<6>
  VSS68  = GND
  DQ7_A  = M_H_CPU1_SA_DQ<7>
  VSS69  = GND
  DQ10_A  = M_H_CPU1_SA_DQ<10>
  VSS70  = GND
  DQ11_A  = M_H_CPU1_SA_DQ<11>
  VSS71  = GND
  \dqs6_a_c||tdqs6_a_c||dqs6_a_t||tdqs6_a_t\  = M_H_CPU1_SA_DQS_DN<6>
  \dqs6_a_t||tdqs6_a_t\  = M_H_CPU1_SA_DQS_DP<6>
  VSS72  = GND
  DQ14_A  = M_H_CPU1_SA_DQ<14>
  VSS73  = GND
  DQ15_A  = M_H_CPU1_SA_DQ<15>
  VSS74  = GND
  DQ18_A  = M_H_CPU1_SA_DQ<18>
  VSS75  = GND
  DQ19_A  = M_H_CPU1_SA_DQ<19>
  VSS76  = GND
  \dqs7_a_c||tdqs7_a_c\  = M_H_CPU1_SA_DQS_DN<7>
  \dqs7_a_t||tdqs7_a_t\  = M_H_CPU1_SA_DQS_DP<7>
  VSS77  = GND
  DQ22_A  = M_H_CPU1_SA_DQ<22>
  VSS78  = GND
  DQ23_A  = M_H_CPU1_SA_DQ<23>
  VSS79  = GND
  DQ26_A  = M_H_CPU1_SA_DQ<26>
  VSS80  = GND
  DQ27_A  = M_H_CPU1_SA_DQ<27>
  VSS81  = GND
  \dqs8_a_c||tdqs8_a_c\  = M_H_CPU1_SA_DQS_DN<8>
  \dqs8_a_t||tdqs8_a_t\  = M_H_CPU1_SA_DQS_DP<8>
  VSS82  = GND
  DQ30_A  = M_H_CPU1_SA_DQ<30>
  VSS83  = GND
  DQ31_A  = M_H_CPU1_SA_DQ<31>
  VSS84  = GND
  CB2_A  = M_H_CPU1_SA_CB<2>
  VSS85  = GND
  CB3_A  = M_H_CPU1_SA_CB<3>
  VSS86  = GND
  \dqs9_a_c||tdqs9_a_c\  = M_H_CPU1_SA_DQS_DN<9>
  \dqs9_a_t||tdqs9_a_t\  = M_H_CPU1_SA_DQS_DP<9>
  VSS87  = GND
  CB6_A  = M_H_CPU1_SA_CB<6>
  VSS88  = GND
  CB7_A  = M_H_CPU1_SA_CB<7>
  VSS89  = GND
  RESET_N  = RST_M_GH_CPU1_FPGA_N
  VSS90  = GND
  CS1_A_N  = M_H_CPU1_SA_CS_N<3>
  VSS91  = GND
  CA1_A  = M_H_CPU1_SA_CA<1>
  VSS92  = GND
  CA3_A  = M_H_CPU1_SA_CA<3>
  VSS93  = GND
  CA5_A  = M_H_CPU1_SA_CA<5>
  VSS94  = GND
  CK_T  = M_H_CPU1_CLK_DP<1>
  CK_C  = M_H_CPU1_CLK_DN<1>
  VSS95  = GND
  RFU4  = TP_CHH_CPU1_DIMM2_FRU_4
  CA1_B  = M_H_CPU1_SB_CA<1>
  VSS96  = GND
  CA3_B  = M_H_CPU1_SB_CA<3>
  VSS97  = GND
  CA5_B  = M_H_CPU1_SB_CA<5>
  VSS98  = GND
  PAR_B  = M_H_CPU1_SB_PAR
  VSS99  = GND
  CS1_B_N  = M_H_CPU1_SB_CS_N<3>
  VSS100  = GND
  RFU5  = TP_CHH_CPU1_DIMM2_FRU_5
  RFU6  = TP_CHH_CPU1_DIMM2_FRU_6
  VSS101  = GND
  CB6_B  = M_H_CPU1_SB_CB<6>
  VSS102  = GND
  CB7_B  = M_H_CPU1_SB_CB<7>
  VSS103  = GND
  DQS4_B_C  = M_H_CPU1_SB_DQS_DN<4>
  DQS4_B_T  = M_H_CPU1_SB_DQS_DP<4>
  VSS104  = GND
  CB2_B  = M_H_CPU1_SB_CB<2>
  VSS105  = GND
  CB3_B  = M_H_CPU1_SB_CB<3>
  VSS106  = GND
  DQ2_B  = M_H_CPU1_SB_DQ<2>
  VSS107  = GND
  DQ3_B  = M_H_CPU1_SB_DQ<3>
  VSS108  = GND
  \dqs5_b_c||tdqs5_b_c\  = M_H_CPU1_SB_DQS_DN<5>
  \dqs5_b_t||tdqs5_b_t\  = M_H_CPU1_SB_DQS_DP<5>
  VSS109  = GND
  DQ6_B  = M_H_CPU1_SB_DQ<6>
  VSS110  = GND
  DQ7_B  = M_H_CPU1_SB_DQ<7>
  VSS111  = GND
  DQ10_B  = M_H_CPU1_SB_DQ<10>
  VSS112  = GND
  DQ11_B  = M_H_CPU1_SB_DQ<11>
  VSS113  = GND
  \dqs6_b_c||tdqs6_b_c\  = M_H_CPU1_SB_DQS_DN<6>
  \dqs6_b_t||tdqs6_b_t\  = M_H_CPU1_SB_DQS_DP<6>
  VSS114  = GND
  DQ14_B  = M_H_CPU1_SB_DQ<14>
  VSS115  = GND
  DQ15_B  = M_H_CPU1_SB_DQ<15>
  VSS116  = GND
  DQ18_B  = M_H_CPU1_SB_DQ<18>
  VSS117  = GND
  DQ19_B  = M_H_CPU1_SB_DQ<19>
  VSS118  = GND
  \dqs7_b_c||tdqs7_b_c\  = M_H_CPU1_SB_DQS_DN<7>
  \dqs7_b_t||tdqs7_b_t\  = M_H_CPU1_SB_DQS_DP<7>
  VSS119  = GND
  DQ22_B  = M_H_CPU1_SB_DQ<22>
  VSS120  = GND
  DQ23_B  = M_H_CPU1_SB_DQ<23>
  VSS121  = GND
  DQ26_B  = M_H_CPU1_SB_DQ<26>
  VSS122  = GND
  DQ27_B  = M_H_CPU1_SB_DQ<27>
  VSS123  = GND
  \dqs8_b_c||tdqs8_b_c\  = M_H_CPU1_SB_DQS_DN<8>
  \dqs8_b_t||tdqs8_b_t\  = M_H_CPU1_SB_DQS_DP<8>
  VSS124  = GND
  DQ30_B  = M_H_CPU1_SB_DQ<30>
  VSS125  = GND
  DQ31_B  = M_H_CPU1_SB_DQ<31>
  VSS126  = GND
  G1  = GND
  G2  = GND
  G3  = GND

(kicad_pcb
	(version 20260206)
	(generator "pcbnew")
	(generator_version "10.0")
	(general
		(thickness 1.6)
		(legacy_teardrops no)
	)
	(paper "A4")
	(title_block
		(title "03242023_DA0F0TMBIJ0_F0T_Motherboard_J_brd_V01_OCP.brd")
		(comment 1 "Grand Teton / footprint 3133 of 6105 (J32), pads 229-274 of 291")
	)
	(layers
		(0 "F.Cu" signal "TOP")
		(4 "In1.Cu" signal "GND")
		(6 "In2.Cu" signal "IN1")
		(8 "In3.Cu" signal "GND1")
		(10 "In4.Cu" signal "IN2")
		(12 "In5.Cu" signal "GND2")
		(14 "In6.Cu" signal "IN3")
		(16 "In7.Cu" signal "GND3")
		(18 "In8.Cu" signal "VCC")
		(20 "In9.Cu" signal "VCC1")
		(22 "In10.Cu" signal "GND4")
		(24 "In11.Cu" signal "IN4")
		(26 "In12.Cu" signal "GND5")
		(28 "In13.Cu" signal "IN5")
		(30 "In14.Cu" signal "GND6")
		(32 "In15.Cu" signal "IN6")
		(34 "In16.Cu" signal "GND7")
		(2 "B.Cu" signal "BOTTOM")
		(9 "F.Adhes" user "F.Adhesive")
		(11 "B.Adhes" user "B.Adhesive")
		(13 "F.Paste" user "Package Geometry/Pastemask Top")
		(15 "B.Paste" user "Package Geometry/Pastemask Bottom")
		(5 "F.SilkS" user "Ref Des/Silkscreen Top")
		(7 "B.SilkS" user "Ref Des/Silkscreen Bottom")
		(1 "F.Mask" user "Board Geometry/Soldermask Top")
		(3 "B.Mask" user "Board Geometry/Soldermask Bottom")
		(17 "Dwgs.User" user "User.Drawings")
		(19 "Cmts.User" user "User.Comments")
		(21 "Eco1.User" user "User.Eco1")
		(23 "Eco2.User" user "User.Eco2")
		(25 "Edge.Cuts" user "Board Geometry/Outline")
		(27 "Margin" user)
		(31 "F.CrtYd" user "Package Geometry/Place Bound Top")
		(29 "B.CrtYd" user "Package Geometry/Place Bound Bottom")
		(35 "F.Fab" user "Ref Des/Assembly Top")
		(33 "B.Fab" user "Ref Des/Assembly Bottom")
	)
	(footprint ""
		(layer "F.Cu")
		(at 206.12608 -258.091686)
		(property "Reference" "J32"
			(at 0.68834 -81.826608 0)
			(unlocked yes)
			(layer "F.SilkS")
			(effects
				(font
					(size 0.7874 0.5842)
					(thickness 0.1524)
				)
				(justify left)
			)
		)
		(property "Value" ""
			(at 0 0 0)
			(layer "F.Fab")
			(effects
				(font
					(size 1.27 1.27)
				)
			)
		)
		(duplicate_pad_numbers_are_jumpers no)
		(pad "229" smd rect
			(at 2.050034 13.17498 270)
			(size 0.519938 1.4986)
			(layers "F.Cu" "F.Mask" "F.Paste")
			(net "M_H_CPU1_SB_CS_N<3>")
		)
		(pad "230" smd rect
			(at 2.050034 14.025118 270)
			(size 0.519938 1.4986)
			(layers "F.Cu" "F.Mask" "F.Paste")
			(net "GND")
		)
		(pad "231" smd rect
			(at 2.050034 14.875002 270)
			(size 0.519938 1.4986)
			(layers "F.Cu" "F.Mask" "F.Paste")
			(net "TP_CHH_CPU1_DIMM2_FRU_5")
		)
		(pad "232" smd rect
			(at 2.050034 15.724886 270)
			(size 0.519938 1.4986)
			(layers "F.Cu" "F.Mask" "F.Paste")
			(net "TP_CHH_CPU1_DIMM2_FRU_6")
		)
		(pad "233" smd rect
			(at 2.050034 16.575024 270)
			(size 0.519938 1.4986)
			(layers "F.Cu" "F.Mask" "F.Paste")
			(net "GND")
		)
		(pad "234" smd rect
			(at 2.050034 17.424908 270)
			(size 0.519938 1.4986)
			(layers "F.Cu" "F.Mask" "F.Paste")
			(net "M_H_CPU1_SB_CB<6>")
		)
		(pad "235" smd rect
			(at 2.050034 18.275046 270)
			(size 0.519938 1.4986)
			(layers "F.Cu" "F.Mask" "F.Paste")
			(net "GND")
		)
		(pad "236" smd rect
			(at 2.050034 19.12493 270)
			(size 0.519938 1.4986)
			(layers "F.Cu" "F.Mask" "F.Paste")
			(net "M_H_CPU1_SB_CB<7>")
		)
		(pad "237" smd rect
			(at 2.050034 19.975068 270)
			(size 0.519938 1.4986)
			(layers "F.Cu" "F.Mask" "F.Paste")
			(net "GND")
		)
		(pad "238" smd rect
			(at 2.050034 20.824952 270)
			(size 0.519938 1.4986)
			(layers "F.Cu" "F.Mask" "F.Paste")
			(net "M_H_CPU1_SB_DQS_DN<4>")
		)
		(pad "239" smd rect
			(at 2.050034 21.67509 270)
			(size 0.519938 1.4986)
			(layers "F.Cu" "F.Mask" "F.Paste")
			(net "M_H_CPU1_SB_DQS_DP<4>")
		)
		(pad "240" smd rect
			(at 2.050034 22.524974 270)
			(size 0.519938 1.4986)
			(layers "F.Cu" "F.Mask" "F.Paste")
			(net "GND")
		)
		(pad "241" smd rect
			(at 2.050034 23.375112 270)
			(size 0.519938 1.4986)
			(layers "F.Cu" "F.Mask" "F.Paste")
			(net "M_H_CPU1_SB_CB<2>")
		)
		(pad "242" smd rect
			(at 2.050034 24.224996 270)
			(size 0.519938 1.4986)
			(layers "F.Cu" "F.Mask" "F.Paste")
			(net "GND")
		)
		(pad "243" smd rect
			(at 2.050034 25.07488 270)
			(size 0.519938 1.4986)
			(layers "F.Cu" "F.Mask" "F.Paste")
			(net "M_H_CPU1_SB_CB<3>")
		)
		(pad "244" smd rect
			(at 2.050034 25.925018 270)
			(size 0.519938 1.4986)
			(layers "F.Cu" "F.Mask" "F.Paste")
			(net "GND")
		)
		(pad "245" smd rect
			(at 2.050034 26.774902 270)
			(size 0.519938 1.4986)
			(layers "F.Cu" "F.Mask" "F.Paste")
			(net "M_H_CPU1_SB_DQ<2>")
		)
		(pad "246" smd rect
			(at 2.050034 27.62504 270)
			(size 0.519938 1.4986)
			(layers "F.Cu" "F.Mask" "F.Paste")
			(net "GND")
		)
		(pad "247" smd rect
			(at 2.050034 28.474924 270)
			(size 0.519938 1.4986)
			(layers "F.Cu" "F.Mask" "F.Paste")
			(net "M_H_CPU1_SB_DQ<3>")
		)
		(pad "248" smd rect
			(at 2.050034 29.325062 270)
			(size 0.519938 1.4986)
			(layers "F.Cu" "F.Mask" "F.Paste")
			(net "GND")
		)
		(pad "249" smd rect
			(at 2.050034 30.174946 270)
			(size 0.519938 1.4986)
			(layers "F.Cu" "F.Mask" "F.Paste")
			(net "M_H_CPU1_SB_DQS_DN<5>")
		)
		(pad "250" smd rect
			(at 2.050034 31.025084 270)
			(size 0.519938 1.4986)
			(layers "F.Cu" "F.Mask" "F.Paste")
			(net "M_H_CPU1_SB_DQS_DP<5>")
		)
		(pad "251" smd rect
			(at 2.050034 31.874968 270)
			(size 0.519938 1.4986)
			(layers "F.Cu" "F.Mask" "F.Paste")
			(net "GND")
		)
		(pad "252" smd rect
			(at 2.050034 32.725106 270)
			(size 0.519938 1.4986)
			(layers "F.Cu" "F.Mask" "F.Paste")
			(net "M_H_CPU1_SB_DQ<6>")
		)
		(pad "253" smd rect
			(at 2.050034 33.57499 270)
			(size 0.519938 1.4986)
			(layers "F.Cu" "F.Mask" "F.Paste")
			(net "GND")
		)
		(pad "254" smd rect
			(at 2.050034 34.425128 270)
			(size 0.519938 1.4986)
			(layers "F.Cu" "F.Mask" "F.Paste")
			(net "M_H_CPU1_SB_DQ<7>")
		)
		(pad "255" smd rect
			(at 2.050034 35.275012 270)
			(size 0.519938 1.4986)
			(layers "F.Cu" "F.Mask" "F.Paste")
			(net "GND")
		)
		(pad "256" smd rect
			(at 2.050034 36.124896 270)
			(size 0.519938 1.4986)
			(layers "F.Cu" "F.Mask" "F.Paste")
			(net "M_H_CPU1_SB_DQ<10>")
		)
		(pad "257" smd rect
			(at 2.050034 36.975034 270)
			(size 0.519938 1.4986)
			(layers "F.Cu" "F.Mask" "F.Paste")
			(net "GND")
		)
		(pad "258" smd rect
			(at 2.050034 37.824918 270)
			(size 0.519938 1.4986)
			(layers "F.Cu" "F.Mask" "F.Paste")
			(net "M_H_CPU1_SB_DQ<11>")
		)
		(pad "259" smd rect
			(at 2.050034 38.675056 270)
			(size 0.519938 1.4986)
			(layers "F.Cu" "F.Mask" "F.Paste")
			(net "GND")
		)
		(pad "260" smd rect
			(at 2.050034 39.52494 270)
			(size 0.519938 1.4986)
			(layers "F.Cu" "F.Mask" "F.Paste")
			(net "M_H_CPU1_SB_DQS_DN<6>")
		)
		(pad "261" smd rect
			(at 2.050034 40.375078 270)
			(size 0.519938 1.4986)
			(layers "F.Cu" "F.Mask" "F.Paste")
			(net "M_H_CPU1_SB_DQS_DP<6>")
		)
		(pad "262" smd rect
			(at 2.050034 41.224962 270)
			(size 0.519938 1.4986)
			(layers "F.Cu" "F.Mask" "F.Paste")
			(net "GND")
		)
		(pad "263" smd rect
			(at 2.050034 42.0751 270)
			(size 0.519938 1.4986)
			(layers "F.Cu" "F.Mask" "F.Paste")
			(net "M_H_CPU1_SB_DQ<14>")
		)
		(pad "264" smd rect
			(at 2.050034 42.924984 270)
			(size 0.519938 1.4986)
			(layers "F.Cu" "F.Mask" "F.Paste")
			(net "GND")
		)
		(pad "265" smd rect
			(at 2.050034 43.775122 270)
			(size 0.519938 1.4986)
			(layers "F.Cu" "F.Mask" "F.Paste")
			(net "M_H_CPU1_SB_DQ<15>")
		)
		(pad "266" smd rect
			(at 2.050034 44.625006 270)
			(size 0.519938 1.4986)
			(layers "F.Cu" "F.Mask" "F.Paste")
			(net "GND")
		)
		(pad "267" smd rect
			(at 2.050034 45.47489 270)
			(size 0.519938 1.4986)
			(layers "F.Cu" "F.Mask" "F.Paste")
			(net "M_H_CPU1_SB_DQ<18>")
		)
		(pad "268" smd rect
			(at 2.050034 46.325028 270)
			(size 0.519938 1.4986)
			(layers "F.Cu" "F.Mask" "F.Paste")
			(net "GND")
		)
		(pad "269" smd rect
			(at 2.050034 47.174912 270)
			(size 0.519938 1.4986)
			(layers "F.Cu" "F.Mask" "F.Paste")
			(net "M_H_CPU1_SB_DQ<19>")
		)
		(pad "270" smd rect
			(at 2.050034 48.02505 270)
			(size 0.519938 1.4986)
			(layers "F.Cu" "F.Mask" "F.Paste")
			(net "GND")
		)
		(pad "271" smd rect
			(at 2.050034 48.874934 270)
			(size 0.519938 1.4986)
			(layers "F.Cu" "F.Mask" "F.Paste")
			(net "M_H_CPU1_SB_DQS_DN<7>")
		)
		(pad "272" smd rect
			(at 2.050034 49.725072 270)
			(size 0.519938 1.4986)
			(layers "F.Cu" "F.Mask" "F.Paste")
			(net "M_H_CPU1_SB_DQS_DP<7>")
		)
		(pad "273" smd rect
			(at 2.050034 50.574956 270)
			(size 0.519938 1.4986)
			(layers "F.Cu" "F.Mask" "F.Paste")
			(net "GND")
		)
		(pad "274" smd rect
			(at 2.050034 51.425094 270)
			(size 0.519938 1.4986)
			(layers "F.Cu" "F.Mask" "F.Paste")
			(net "M_H_CPU1_SB_DQ<22>")
		)
	)
)
